DEVICE-TYPE           GERBER_RS274X
OUTPUT-UNITS          INCHES
FILM-SIZE             2400000 1600000
FORMAT                5.5
ABORT-ON-ERROR        NO
SCALE                 1
SUPPRESS-LEAD-ZEROES  YES
SUPPRESS-TRAIL-ZEROES NO
SUPPRESS-EQUAL        YES
UNDEF-APT-CONT        NO
